# BASEBOARD_FAB2 (Tioga Pass) — schematic netlist excerpt (pin names and nets, part order shuffled) for the footprints in the layout excerpt that follows; sources: Cadence DE-HDL packaged netlist, KiCad conversion of Wiwynn_Tioga_Pass_MB.brd

J4A1  SCONN288_H44441004  SCONN  pkg PIP  page 53
  \12v\(1)  = P12V_NVDIMM_DEF
  VSS(93)  = GND
  DQ(4)  = M_F_DQ<5>
  VSS(92)  = GND
  DQ(0)  = M_F_DQ<1>
  VSS(91)  = GND
  DQS9P  = M_F_DQS_DP<9>
  DQS9N  = M_F_DQS_DN<9>
  VSS(90)  = GND
  DQ(6)  = M_F_DQ<7>
  VSS(89)  = GND
  DQ(2)  = M_F_DQ<3>
  VSS(88)  = GND
  DQ(12)  = M_F_DQ<13>
  VSS(87)  = GND
  DQ(8)  = M_F_DQ<9>
  VSS(86)  = GND
  DQS10P  = M_F_DQS_DP<10>
  DQS10N  = M_F_DQS_DN<10>
  VSS(85)  = GND
  DQ(14)  = M_F_DQ<15>
  VSS(84)  = GND
  DQ(10)  = M_F_DQ<11>
  VSS(83)  = GND
  DQ(20)  = M_F_DQ<21>
  VSS(82)  = GND
  DQ(16)  = M_F_DQ<17>
  VSS(81)  = GND
  DQS11P  = M_F_DQS_DP<11>
  DQS11N  = M_F_DQS_DN<11>
  VSS(80)  = GND
  DQ(22)  = M_F_DQ<23>
  VSS(79)  = GND
  DQ(18)  = M_F_DQ<19>
  VSS(78)  = GND
  DQ(28)  = M_F_DQ<29>
  VSS(77)  = GND
  DQ(24)  = M_F_DQ<25>
  VSS(76)  = GND
  DQS12P  = M_F_DQS_DP<12>
  DQS12N  = M_F_DQS_DN<12>
  VSS(75)  = GND
  DQ(30)  = M_F_DQ<31>
  VSS(74)  = GND
  DQ(26)  = M_F_DQ<27>
  VSS(73)  = GND
  CB(4)  = M_F_ECC<5>
  VSS(72)  = GND
  CB(0)  = M_F_ECC<1>
  VSS(71)  = GND
  DQS17P  = M_F_DQS_DP<17>
  DQS17N  = M_F_DQS_DN<17>
  VSS(70)  = GND
  CB(6)  = M_F_ECC<7>
  VSS(69)  = GND
  CB(2)  = M_F_ECC<3>
  VSS(68)  = GND
  RESET_N  = M_DEF_RST_N
  VDD(25)  = PVDDQ_DEF
  CKE(0)  = M_F_CKE<0>
  VDD(24)  = PVDDQ_DEF
  ACT_N  = M_F_ACT_N
  BG(0)  = M_F_BG<0>
  VDD(23)  = PVDDQ_DEF
  A12  = M_F_MA<12>
  A9  = M_F_MA<9>
  VDD(22)  = PVDDQ_DEF
  A8  = M_F_MA<8>
  A6  = M_F_MA<6>
  VDD(21)  = PVDDQ_DEF
  A3  = M_F_MA<3>
  A1  = M_F_MA<1>
  VDD(20)  = PVDDQ_DEF
  CK0P  = M_F_CLK_DP<0>
  CK0N  = M_F_CLK_DN<0>
  VDD(19)  = PVDDQ_DEF
  VTT(1)  = PVTT_DEF
  EVENT_N  = FM_DIMM_EVENT_COD_N
  A0  = M_F_MA<0>
  VDD(18)  = PVDDQ_DEF
  BA(0)  = M_F_BA<0>
  A16_RAS_N  = M_F_MA<16>
  VDD(17)  = PVDDQ_DEF
  S0_N  = M_F_CS_N<0>
  VDD(16)  = PVDDQ_DEF
  A15_CAS_N  = M_F_MA<15>
  ODT(0)  = M_F_ODT<0>
  VDD(15)  = PVDDQ_DEF
  S1_N  = M_F_CS_N<1>
  VDD(14)  = PVDDQ_DEF
  ODT(1)  = M_F_ODT<1>
  VDD(13)  = PVDDQ_DEF
  S2_N_C(0)  = M_F_CS_N<2>
  VSS(67)  = GND
  DQ(36)  = M_F_DQ<37>
  VSS(66)  = GND
  DQ(32)  = M_F_DQ<33>
  VSS(65)  = GND
  DQS13P  = M_F_DQS_DP<13>
  DQS13N  = M_F_DQS_DN<13>
  VSS(64)  = GND
  DQ(38)  = M_F_DQ<39>
  VSS(63)  = GND
  DQ(34)  = M_F_DQ<35>
  VSS(62)  = GND
  DQ(44)  = M_F_DQ<45>
  VSS(61)  = GND
  DQ(40)  = M_F_DQ<41>
  VSS(60)  = GND
  DQS14P  = M_F_DQS_DP<14>
  DQS14N  = M_F_DQS_DN<14>
  VSS(59)  = GND
  DQ(46)  = M_F_DQ<47>
  VSS(58)  = GND
  DQ(42)  = M_F_DQ<43>
  VSS(57)  = GND
  DQ(52)  = M_F_DQ<53>
  VSS(56)  = GND
  DQ(48)  = M_F_DQ<49>
  VSS(55)  = GND
  DQS15P  = M_F_DQS_DP<15>
  DQS15N  = M_F_DQS_DN<15>
  VSS(54)  = GND
  DQ(54)  = M_F_DQ<55>
  VSS(53)  = GND
  DQ(50)  = M_F_DQ<51>
  VSS(52)  = GND
  DQ(60)  = M_F_DQ<61>
  VSS(51)  = GND
  DQ(56)  = M_F_DQ<57>
  VSS(50)  = GND
  DQS16P  = M_F_DQS_DP<16>
  DQS16N  = M_F_DQS_DN<16>
  VSS(49)  = GND
  DQ(62)  = M_F_DQ<63>
  VSS(48)  = GND
  DQ(58)  = M_F_DQ<59>
  VSS(47)  = GND
  SA(0)  = GND
  SA(1)  = GND
  SCL  = SMB_DDR_DEF_VPP_SCL
  VPP(4)  = PVPP_DEF
  VPP(3)  = PVPP_DEF
  RFU(2)  = TP_CH_F_DIMM_F0_RFU_2
  \12v\(0)  = P12V_NVDIMM_DEF
  VREFCA  = M_F_VREF
  VSS(46)  = GND
  DQ(5)  = M_F_DQ<4>
  VSS(45)  = GND
  DQ(1)  = M_F_DQ<0>
  VSS(44)  = GND
  DQS0N  = M_F_DQS_DN<0>
  DQS0P  = M_F_DQS_DP<0>
  VSS(43)  = GND
  DQ(7)  = M_F_DQ<6>
  VSS(42)  = GND
  DQ(3)  = M_F_DQ<2>
  VSS(41)  = GND
  DQ(13)  = M_F_DQ<12>
  VSS(40)  = GND
  DQ(9)  = M_F_DQ<8>
  VSS(39)  = GND
  DQS1N  = M_F_DQS_DN<1>
  DQS1P  = M_F_DQS_DP<1>
  VSS(38)  = GND
  DQ(15)  = M_F_DQ<14>
  VSS(37)  = GND
  DQ(11)  = M_F_DQ<10>
  VSS(36)  = GND
  DQ(21)  = M_F_DQ<20>
  VSS(35)  = GND
  DQ(17)  = M_F_DQ<16>
  VSS(34)  = GND
  DQS2N  = M_F_DQS_DN<2>
  DQS2P  = M_F_DQS_DP<2>
  VSS(33)  = GND
  DQ(23)  = M_F_DQ<22>
  VSS(32)  = GND
  DQ(19)  = M_F_DQ<18>
  VSS(31)  = GND
  DQ(29)  = M_F_DQ<28>
  VSS(30)  = GND
  DQ(25)  = M_F_DQ<24>
  VSS(29)  = GND
  DQS3N  = M_F_DQS_DN<3>
  DQS3P  = M_F_DQS_DP<3>
  VSS(28)  = GND
  DQ(31)  = M_F_DQ<30>
  VSS(27)  = GND
  DQ(27)  = M_F_DQ<26>
  VSS(26)  = GND
  CB(5)  = M_F_ECC<4>
  VSS(25)  = GND
  CB(1)  = M_F_ECC<0>
  VSS(24)  = GND
  DQS8N  = M_F_DQS_DN<8>
  DQS8P  = M_F_DQS_DP<8>
  VSS(23)  = GND
  CB(7)  = M_F_ECC<6>
  VSS(22)  = GND
  CB(3)  = M_F_ECC<2>
  VSS(21)  = GND
  CKE(1)  = M_F_CKE<1>
  VDD(12)  = PVDDQ_DEF
  RFU(0)  = TP_CH_F_DIMM_F0_RFU_0
  VDD(11)  = PVDDQ_DEF
  BG(1)  = M_F_BG<1>
  ALERT_N  = M_F_ALERT_N
  VDD(10)  = PVDDQ_DEF
  A11  = M_F_MA<11>
  A7  = M_F_MA<7>
  VDD(9)  = PVDDQ_DEF
  A5  = M_F_MA<5>
  A4  = M_F_MA<4>
  VDD(8)  = PVDDQ_DEF
  A2  = M_F_MA<2>
  VDD(7)  = PVDDQ_DEF
  CK1P  = M_F_CLK_DP<1>
  CK1N  = M_F_CLK_DN<1>
  VDD(6)  = PVDDQ_DEF
  VTT(0)  = PVTT_DEF
  PAR  = M_F_PAR
  VDD(5)  = PVDDQ_DEF
  BA(1)  = M_F_BA<1>
  A10  = M_F_MA<10>
  VDD(4)  = PVDDQ_DEF
  RFU(1)  = TP_CH_F_DIMM_F0_RFU_1
  A14_WE_N  = M_F_MA<14>
  VDD(3)  = PVDDQ_DEF
  SAVE_N_NC  = FM_ADR_COMPLETE_DEF_N
  VDD(2)  = PVDDQ_DEF
  A13  = M_F_MA<13>
  VDD(1)  = PVDDQ_DEF
  A17  = M_F_MA<17>
  C(2)  = M_F_C<2>
  VDD(0)  = PVDDQ_DEF
  S3_N_C(1)  = M_F_CS_N<3>
  SA(2)  = PVPP_DEF
  VSS(20)  = GND
  DQ(37)  = M_F_DQ<36>
  VSS(19)  = GND
  DQ(33)  = M_F_DQ<32>
  VSS(18)  = GND
  DQS4N  = M_F_DQS_DN<4>
  DQS4P  = M_F_DQS_DP<4>
  VSS(17)  = GND
  DQ(39)  = M_F_DQ<38>
  VSS(16)  = GND
  DQ(35)  = M_F_DQ<34>
  VSS(15)  = GND
  DQ(45)  = M_F_DQ<44>
  VSS(14)  = GND
  DQ(41)  = M_F_DQ<40>
  VSS(13)  = GND
  DQS5N  = M_F_DQS_DN<5>
  DQS5P  = M_F_DQS_DP<5>
  VSS(12)  = GND
  DQ(47)  = M_F_DQ<46>
  VSS(11)  = GND
  DQ(43)  = M_F_DQ<42>
  VSS(10)  = GND
  DQ(53)  = M_F_DQ<52>
  VSS(9)  = GND
  DQ(49)  = M_F_DQ<48>
  VSS(8)  = GND
  DQS6N  = M_F_DQS_DN<6>
  DQS6P  = M_F_DQS_DP<6>
  VSS(7)  = GND
  DQ(55)  = M_F_DQ<54>
  VSS(6)  = GND
  DQ(51)  = M_F_DQ<50>
  VSS(5)  = GND
  DQ(61)  = M_F_DQ<60>
  VSS(4)  = GND
  DQ(57)  = M_F_DQ<56>
  VSS(3)  = GND
  DQS7N  = M_F_DQS_DN<7>
  DQS7P  = M_F_DQS_DP<7>
  VSS(2)  = GND
  DQ(63)  = M_F_DQ<62>
  VSS(1)  = GND
  DQ(59)  = M_F_DQ<58>
  VSS(0)  = GND
  VDDSPD  = PVPP_DEF
  SDA  = SMB_DDR_DEF_VPP_SDA
  VPP(1)  = PVPP_DEF
  VPP(0)  = PVPP_DEF
  VPP(2)  = PVPP_DEF

(kicad_pcb
	(version 20260206)
	(generator "pcbnew")
	(generator_version "10.0")
	(general
		(thickness 1.6)
		(legacy_teardrops no)
	)
	(paper "A4")
	(title_block
		(title "Wiwynn_Tioga_Pass_MB.brd")
		(comment 1 "Tioga Pass / footprint 431 of 4770 (J4A1), pads 153-202 of 291")
	)
	(layers
		(0 "F.Cu" signal "TOP")
		(4 "In1.Cu" signal "L2GND")
		(6 "In2.Cu" signal "L3")
		(8 "In3.Cu" signal "L4GND")
		(10 "In4.Cu" signal "L5")
		(12 "In5.Cu" signal "L6GND")
		(14 "In6.Cu" signal "L7VCC")
		(16 "In7.Cu" signal "L8VCC")
		(18 "In8.Cu" signal "L9GND")
		(20 "In9.Cu" signal "L10")
		(22 "In10.Cu" signal "L11GND")
		(24 "In11.Cu" signal "L12")
		(26 "In12.Cu" signal "L13GND")
		(2 "B.Cu" signal "BOTTOM")
		(9 "F.Adhes" user "F.Adhesive")
		(11 "B.Adhes" user "B.Adhesive")
		(13 "F.Paste" user "Package Geometry/Pastemask Top")
		(15 "B.Paste" user "Package Geometry/Pastemask Bottom")
		(5 "F.SilkS" user "Ref Des/Silkscreen Top")
		(7 "B.SilkS" user "Ref Des/Silkscreen Bottom")
		(1 "F.Mask" user "Board Geometry/Soldermask Top")
		(3 "B.Mask" user "Board Geometry/Soldermask Bottom")
		(17 "Dwgs.User" user "User.Drawings")
		(19 "Cmts.User" user "User.Comments")
		(21 "Eco1.User" user "User.Eco1")
		(23 "Eco2.User" user "User.Eco2")
		(25 "Edge.Cuts" user "Board Geometry/Outline")
		(27 "Margin" user)
		(31 "F.CrtYd" user "Package Geometry/Place Bound Top")
		(29 "B.CrtYd" user "Package Geometry/Place Bound Bottom")
		(35 "F.Fab" user "Ref Des/Assembly Top")
		(33 "B.Fab" user "Ref Des/Assembly Bottom")
	)
	(footprint ""
		(layer "F.Cu")
		(at 194.700398 -152.273 90)
		(property "Reference" "J4A1"
			(at -2.699512 42.53611 0)
			(unlocked yes)
			(layer "F.SilkS")
			(effects
				(font
					(size 0.7874 0.5842)
					(thickness 0.1524)
				)
				(justify left)
			)
		)
		(property "Value" ""
			(at 0 0 90)
			(layer "F.Fab")
			(effects
				(font
					(size 1.27 1.27)
				)
			)
		)
		(duplicate_pad_numbers_are_jumpers no)
		(pad "150" smd rect
			(at 4.59994 4.249928 90)
			(size 1.8034 0.508)
			(layers "F.Cu" "F.Mask" "F.Paste")
			(net "M_F_DQ<0>")
		)
		(pad "151" smd rect
			(at 4.59994 5.100066 90)
			(size 1.8034 0.508)
			(layers "F.Cu" "F.Mask" "F.Paste")
			(net "GND")
		)
		(pad "152" smd rect
			(at 4.59994 5.94995 90)
			(size 1.8034 0.508)
			(layers "F.Cu" "F.Mask" "F.Paste")
			(net "M_F_DQS_DN<0>")
		)
		(pad "153" smd rect
			(at 4.59994 6.800088 90)
			(size 1.8034 0.508)
			(layers "F.Cu" "F.Mask" "F.Paste")
			(net "M_F_DQS_DP<0>")
		)
		(pad "154" smd rect
			(at 4.59994 7.649972 90)
			(size 1.8034 0.508)
			(layers "F.Cu" "F.Mask" "F.Paste")
			(net "GND")
		)
		(pad "155" smd rect
			(at 4.59994 8.50011 90)
			(size 1.8034 0.508)
			(layers "F.Cu" "F.Mask" "F.Paste")
			(net "M_F_DQ<6>")
		)
		(pad "156" smd rect
			(at 4.59994 9.349994 90)
			(size 1.8034 0.508)
			(layers "F.Cu" "F.Mask" "F.Paste")
			(net "GND")
		)
		(pad "157" smd rect
			(at 4.59994 10.199878 90)
			(size 1.8034 0.508)
			(layers "F.Cu" "F.Mask" "F.Paste")
			(net "M_F_DQ<2>")
		)
		(pad "158" smd rect
			(at 4.59994 11.050016 90)
			(size 1.8034 0.508)
			(layers "F.Cu" "F.Mask" "F.Paste")
			(net "GND")
		)
		(pad "159" smd rect
			(at 4.59994 11.8999 90)
			(size 1.8034 0.508)
			(layers "F.Cu" "F.Mask" "F.Paste")
			(net "M_F_DQ<12>")
		)
		(pad "160" smd rect
			(at 4.59994 12.750038 90)
			(size 1.8034 0.508)
			(layers "F.Cu" "F.Mask" "F.Paste")
			(net "GND")
		)
		(pad "161" smd rect
			(at 4.59994 13.599922 90)
			(size 1.8034 0.508)
			(layers "F.Cu" "F.Mask" "F.Paste")
			(net "M_F_DQ<8>")
		)
		(pad "162" smd rect
			(at 4.59994 14.45006 90)
			(size 1.8034 0.508)
			(layers "F.Cu" "F.Mask" "F.Paste")
			(net "GND")
		)
		(pad "163" smd rect
			(at 4.59994 15.299944 90)
			(size 1.8034 0.508)
			(layers "F.Cu" "F.Mask" "F.Paste")
			(net "M_F_DQS_DN<1>")
		)
		(pad "164" smd rect
			(at 4.59994 16.150082 90)
			(size 1.8034 0.508)
			(layers "F.Cu" "F.Mask" "F.Paste")
			(net "M_F_DQS_DP<1>")
		)
		(pad "165" smd rect
			(at 4.59994 16.999966 90)
			(size 1.8034 0.508)
			(layers "F.Cu" "F.Mask" "F.Paste")
			(net "GND")
		)
		(pad "166" smd rect
			(at 4.59994 17.850104 90)
			(size 1.8034 0.508)
			(layers "F.Cu" "F.Mask" "F.Paste")
			(net "M_F_DQ<14>")
		)
		(pad "167" smd rect
			(at 4.59994 18.699988 90)
			(size 1.8034 0.508)
			(layers "F.Cu" "F.Mask" "F.Paste")
			(net "GND")
		)
		(pad "168" smd rect
			(at 4.59994 19.550126 90)
			(size 1.8034 0.508)
			(layers "F.Cu" "F.Mask" "F.Paste")
			(net "M_F_DQ<10>")
		)
		(pad "169" smd rect
			(at 4.59994 20.40001 90)
			(size 1.8034 0.508)
			(layers "F.Cu" "F.Mask" "F.Paste")
			(net "GND")
		)
		(pad "170" smd rect
			(at 4.59994 21.249894 90)
			(size 1.8034 0.508)
			(layers "F.Cu" "F.Mask" "F.Paste")
			(net "M_F_DQ<20>")
		)
		(pad "171" smd rect
			(at 4.59994 22.100032 90)
			(size 1.8034 0.508)
			(layers "F.Cu" "F.Mask" "F.Paste")
			(net "GND")
		)
		(pad "172" smd rect
			(at 4.59994 22.949916 90)
			(size 1.8034 0.508)
			(layers "F.Cu" "F.Mask" "F.Paste")
			(net "M_F_DQ<16>")
		)
		(pad "173" smd rect
			(at 4.59994 23.800054 90)
			(size 1.8034 0.508)
			(layers "F.Cu" "F.Mask" "F.Paste")
			(net "GND")
		)
		(pad "174" smd rect
			(at 4.59994 24.649938 90)
			(size 1.8034 0.508)
			(layers "F.Cu" "F.Mask" "F.Paste")
			(net "M_F_DQS_DN<2>")
		)
		(pad "175" smd rect
			(at 4.59994 25.500076 90)
			(size 1.8034 0.508)
			(layers "F.Cu" "F.Mask" "F.Paste")
			(net "M_F_DQS_DP<2>")
		)
		(pad "176" smd rect
			(at 4.59994 26.34996 90)
			(size 1.8034 0.508)
			(layers "F.Cu" "F.Mask" "F.Paste")
			(net "GND")
		)
		(pad "177" smd rect
			(at 4.59994 27.200098 90)
			(size 1.8034 0.508)
			(layers "F.Cu" "F.Mask" "F.Paste")
			(net "M_F_DQ<22>")
		)
		(pad "178" smd rect
			(at 4.59994 28.049982 90)
			(size 1.8034 0.508)
			(layers "F.Cu" "F.Mask" "F.Paste")
			(net "GND")
		)
		(pad "179" smd rect
			(at 4.59994 28.90012 90)
			(size 1.8034 0.508)
			(layers "F.Cu" "F.Mask" "F.Paste")
			(net "M_F_DQ<18>")
		)
		(pad "180" smd rect
			(at 4.59994 29.750004 90)
			(size 1.8034 0.508)
			(layers "F.Cu" "F.Mask" "F.Paste")
			(net "GND")
		)
		(pad "181" smd rect
			(at 4.59994 30.599888 90)
			(size 1.8034 0.508)
			(layers "F.Cu" "F.Mask" "F.Paste")
			(net "M_F_DQ<28>")
		)
		(pad "182" smd rect
			(at 4.59994 31.450026 90)
			(size 1.8034 0.508)
			(layers "F.Cu" "F.Mask" "F.Paste")
			(net "GND")
		)
		(pad "183" smd rect
			(at 4.59994 32.29991 90)
			(size 1.8034 0.508)
			(layers "F.Cu" "F.Mask" "F.Paste")
			(net "M_F_DQ<24>")
		)
		(pad "184" smd rect
			(at 4.59994 33.150048 90)
			(size 1.8034 0.508)
			(layers "F.Cu" "F.Mask" "F.Paste")
			(net "GND")
		)
		(pad "185" smd rect
			(at 4.59994 33.999932 90)
			(size 1.8034 0.508)
			(layers "F.Cu" "F.Mask" "F.Paste")
			(net "M_F_DQS_DN<3>")
		)
		(pad "186" smd rect
			(at 4.59994 34.85007 90)
			(size 1.8034 0.508)
			(layers "F.Cu" "F.Mask" "F.Paste")
			(net "M_F_DQS_DP<3>")
		)
		(pad "187" smd rect
			(at 4.59994 35.699954 90)
			(size 1.8034 0.508)
			(layers "F.Cu" "F.Mask" "F.Paste")
			(net "GND")
		)
		(pad "188" smd rect
			(at 4.59994 36.550092 90)
			(size 1.8034 0.508)
			(layers "F.Cu" "F.Mask" "F.Paste")
			(net "M_F_DQ<30>")
		)
		(pad "189" smd rect
			(at 4.59994 37.399976 90)
			(size 1.8034 0.508)
			(layers "F.Cu" "F.Mask" "F.Paste")
			(net "GND")
		)
		(pad "190" smd rect
			(at 4.59994 38.250114 90)
			(size 1.8034 0.508)
			(layers "F.Cu" "F.Mask" "F.Paste")
			(net "M_F_DQ<26>")
		)
		(pad "191" smd rect
			(at 4.59994 39.099998 90)
			(size 1.8034 0.508)
			(layers "F.Cu" "F.Mask" "F.Paste")
			(net "GND")
		)
		(pad "192" smd rect
			(at 4.59994 39.949882 90)
			(size 1.8034 0.508)
			(layers "F.Cu" "F.Mask" "F.Paste")
			(net "M_F_ECC<4>")
		)
		(pad "193" smd rect
			(at 4.59994 40.80002 90)
			(size 1.8034 0.508)
			(layers "F.Cu" "F.Mask" "F.Paste")
			(net "GND")
		)
		(pad "194" smd rect
			(at 4.59994 41.649904 90)
			(size 1.8034 0.508)
			(layers "F.Cu" "F.Mask" "F.Paste")
			(net "M_F_ECC<0>")
		)
		(pad "195" smd rect
			(at 4.59994 42.500042 90)
			(size 1.8034 0.508)
			(layers "F.Cu" "F.Mask" "F.Paste")
			(net "GND")
		)
		(pad "196" smd rect
			(at 4.59994 43.349926 90)
			(size 1.8034 0.508)
			(layers "F.Cu" "F.Mask" "F.Paste")
			(net "M_F_DQS_DN<8>")
		)
		(pad "197" smd rect
			(at 4.59994 44.200064 90)
			(size 1.8034 0.508)
			(layers "F.Cu" "F.Mask" "F.Paste")
			(net "M_F_DQS_DP<8>")
		)
		(pad "198" smd rect
			(at 4.59994 45.049948 90)
			(size 1.8034 0.508)
			(layers "F.Cu" "F.Mask" "F.Paste")
			(net "GND")
		)
		(pad "199" smd rect
			(at 4.59994 45.900086 90)
			(size 1.8034 0.508)
			(layers "F.Cu" "F.Mask" "F.Paste")
			(net "M_F_ECC<6>")
		)
	)
)
